(kicad_pcb
	(version 20260206)
	(generator "pcbnew")
	(generator_version "10.0")
	(general
		(thickness 1.6)
		(legacy_teardrops no)
	)
	(paper "A4")
	(title_block
		(title "Wiwynn_Tioga_Pass_MB.brd")
		(comment 1 "Tioga Pass / footprints 1956-1963 of 4770")
	)
	(layers
		(0 "F.Cu" signal "TOP")
		(4 "In1.Cu" signal "L2GND")
		(6 "In2.Cu" signal "L3")
		(8 "In3.Cu" signal "L4GND")
		(10 "In4.Cu" signal "L5")
		(12 "In5.Cu" signal "L6GND")
		(14 "In6.Cu" signal "L7VCC")
		(16 "In7.Cu" signal "L8VCC")
		(18 "In8.Cu" signal "L9GND")
		(20 "In9.Cu" signal "L10")
		(22 "In10.Cu" signal "L11GND")
		(24 "In11.Cu" signal "L12")
		(26 "In12.Cu" signal "L13GND")
		(2 "B.Cu" signal "BOTTOM")
		(9 "F.Adhes" user "F.Adhesive")
		(11 "B.Adhes" user "B.Adhesive")
		(13 "F.Paste" user "Package Geometry/Pastemask Top")
		(15 "B.Paste" user "Package Geometry/Pastemask Bottom")
		(5 "F.SilkS" user "Ref Des/Silkscreen Top")
		(7 "B.SilkS" user "Ref Des/Silkscreen Bottom")
		(1 "F.Mask" user "Board Geometry/Soldermask Top")
		(3 "B.Mask" user "Board Geometry/Soldermask Bottom")
		(17 "Dwgs.User" user "User.Drawings")
		(19 "Cmts.User" user "User.Comments")
		(21 "Eco1.User" user "User.Eco1")
		(23 "Eco2.User" user "User.Eco2")
		(25 "Edge.Cuts" user "Board Geometry/Outline")
		(27 "Margin" user)
		(31 "F.CrtYd" user "Package Geometry/Place Bound Top")
		(29 "B.CrtYd" user "Package Geometry/Place Bound Bottom")
		(35 "F.Fab" user "Ref Des/Assembly Top")
		(33 "B.Fab" user "Ref Des/Assembly Bottom")
	)
	(footprint ""
		(layer "F.Cu")
		(at 113.332768 -79.6036 180)
		(property "Reference" "C3D8"
			(at 0 0 180)
			(layer "F.SilkS")
			(hide yes)
			(effects
				(font
					(size 1.27 1.27)
				)
			)
		)
		(property "Value" ""
			(at 0 0 180)
			(layer "F.Fab")
			(effects
				(font
					(size 1.27 1.27)
				)
			)
		)
		(duplicate_pad_numbers_are_jumpers no)
		(fp_poly
			(pts
				(xy -0.4953 -0.2032) (xy 0.4953 -0.2032) (xy 0.4953 1.6002) (xy -0.4953 1.6002)
			)
			(stroke
				(width 0)
				(type default)
			)
			(fill no)
			(layer "F.CrtYd")
		)
		(fp_line
			(start 0.4953 1.6002)
			(end -0.4953 1.6002)
			(stroke
				(width 0.1)
				(type default)
			)
			(layer "F.Fab")
		)
		(fp_line
			(start 0.4953 -0.2032)
			(end 0.4953 1.6002)
			(stroke
				(width 0.1)
				(type default)
			)
			(layer "F.Fab")
		)
		(fp_line
			(start -0.4953 1.6002)
			(end -0.4953 -0.2032)
			(stroke
				(width 0.1)
				(type default)
			)
			(layer "F.Fab")
		)
		(fp_line
			(start -0.4953 -0.2032)
			(end 0.4953 -0.2032)
			(stroke
				(width 0.1)
				(type default)
			)
			(layer "F.Fab")
		)
		(pad "1" smd rect
			(at 0 0 180)
			(size 0.762 0.889)
			(layers "F.Cu" "F.Mask" "F.Paste")
			(net "PVCCIO_CPU1")
		)
		(pad "2" smd rect
			(at 0 1.397 180)
			(size 0.762 0.889)
			(layers "F.Cu" "F.Mask" "F.Paste")
			(net "GND")
		)
		(zone
			(layer "F.Cu")
			(hatch none 0.5)
			(connect_pads
				(clearance 0)
			)
			(min_thickness 0.25)
			(keepout
				(tracks not_allowed)
				(vias allowed)
				(pads allowed)
				(copperpour not_allowed)
				(footprints allowed)
			)
			(placement
				(enabled no)
				(sheetname "")
			)
			(fill
				(thermal_gap 0.5)
				(thermal_bridge_width 0.5)
				(island_removal_mode 0)
			)
			(polygon
				(pts
					(xy 113.713768 -80.0481) (xy 112.951768 -80.0481) (xy 112.951768 -80.5561) (xy 113.713768 -80.5561)
				)
			)
		)
	)
	(footprint ""
		(layer "F.Cu")
		(at 19.2024 -84.3534)
		(property "Reference" "R1D13"
			(at 0 0 0)
			(layer "F.SilkS")
			(hide yes)
			(effects
				(font
					(size 1.27 1.27)
				)
			)
		)
		(property "Value" ""
			(at 0 0 0)
			(layer "F.Fab")
			(effects
				(font
					(size 1.27 1.27)
				)
			)
		)
		(duplicate_pad_numbers_are_jumpers no)
		(fp_poly
			(pts
				(xy -0.2794 -0.1016) (xy 0.2794 -0.1016) (xy 0.2794 0.9906) (xy -0.2794 0.9906)
			)
			(stroke
				(width 0)
				(type default)
			)
			(fill no)
			(layer "F.CrtYd")
		)
		(fp_line
			(start -0.2794 -0.1016)
			(end -0.2794 0.9906)
			(stroke
				(width 0.1)
				(type default)
			)
			(layer "F.Fab")
		)
		(fp_line
			(start -0.2794 0.9906)
			(end 0.2794 0.9906)
			(stroke
				(width 0.1)
				(type default)
			)
			(layer "F.Fab")
		)
		(fp_line
			(start 0.2794 -0.1016)
			(end -0.2794 -0.1016)
			(stroke
				(width 0.1)
				(type default)
			)
			(layer "F.Fab")
		)
		(fp_line
			(start 0.2794 0.9906)
			(end 0.2794 -0.1016)
			(stroke
				(width 0.1)
				(type default)
			)
			(layer "F.Fab")
		)
		(pad "1" smd rect
			(at 0 0)
			(size 0.508 0.508)
			(layers "F.Cu" "F.Mask" "F.Paste")
			(net "A_HSC_ISET_S")
		)
		(pad "2" smd rect
			(at 0 0.889)
			(size 0.508 0.508)
			(layers "F.Cu" "F.Mask" "F.Paste")
			(net "A_HSC_ISET")
		)
		(zone
			(layer "F.Cu")
			(hatch none 0.5)
			(connect_pads
				(clearance 0)
			)
			(min_thickness 0.25)
			(keepout
				(tracks allowed)
				(vias not_allowed)
				(pads allowed)
				(copperpour not_allowed)
				(footprints allowed)
			)
			(placement
				(enabled no)
				(sheetname "")
			)
			(fill
				(thermal_gap 0.5)
				(thermal_bridge_width 0.5)
				(island_removal_mode 0)
			)
			(polygon
				(pts
					(xy 18.9484 -84.0994) (xy 19.4564 -84.0994) (xy 19.4564 -83.7184) (xy 18.9484 -83.7184)
				)
			)
		)
		(zone
			(layer "F.Cu")
			(hatch none 0.5)
			(connect_pads
				(clearance 0)
			)
			(min_thickness 0.25)
			(keepout
				(tracks not_allowed)
				(vias allowed)
				(pads allowed)
				(copperpour not_allowed)
				(footprints allowed)
			)
			(placement
				(enabled no)
				(sheetname "")
			)
			(fill
				(thermal_gap 0.5)
				(thermal_bridge_width 0.5)
				(island_removal_mode 0)
			)
			(polygon
				(pts
					(xy 18.9484 -83.7184) (xy 19.4564 -83.7184) (xy 19.4564 -84.0994) (xy 18.9484 -84.0994)
				)
			)
		)
	)
	(footprint ""
		(layer "F.Cu")
		(at 105.62844 -73.279)
		(property "Reference" "C2D40"
			(at 0 0 0)
			(layer "F.SilkS")
			(hide yes)
			(effects
				(font
					(size 1.27 1.27)
				)
			)
		)
		(property "Value" ""
			(at 0 0 0)
			(layer "F.Fab")
			(effects
				(font
					(size 1.27 1.27)
				)
			)
		)
		(duplicate_pad_numbers_are_jumpers no)
		(fp_poly
			(pts
				(xy -0.4953 -0.2032) (xy 0.4953 -0.2032) (xy 0.4953 1.6002) (xy -0.4953 1.6002)
			)
			(stroke
				(width 0)
				(type default)
			)
			(fill no)
			(layer "F.CrtYd")
		)
		(fp_line
			(start -0.4953 -0.2032)
			(end 0.4953 -0.2032)
			(stroke
				(width 0.1)
				(type default)
			)
			(layer "F.Fab")
		)
		(fp_line
			(start -0.4953 1.6002)
			(end -0.4953 -0.2032)
			(stroke
				(width 0.1)
				(type default)
			)
			(layer "F.Fab")
		)
		(fp_line
			(start 0.4953 -0.2032)
			(end 0.4953 1.6002)
			(stroke
				(width 0.1)
				(type default)
			)
			(layer "F.Fab")
		)
		(fp_line
			(start 0.4953 1.6002)
			(end -0.4953 1.6002)
			(stroke
				(width 0.1)
				(type default)
			)
			(layer "F.Fab")
		)
		(pad "1" smd rect
			(at 0 0)
			(size 0.762 0.889)
			(layers "F.Cu" "F.Mask" "F.Paste")
			(net "PVCCMCP_CPU1")
		)
		(pad "2" smd rect
			(at 0 1.397)
			(size 0.762 0.889)
			(layers "F.Cu" "F.Mask" "F.Paste")
			(net "GND")
		)
		(zone
			(layer "F.Cu")
			(hatch none 0.5)
			(connect_pads
				(clearance 0)
			)
			(min_thickness 0.25)
			(keepout
				(tracks not_allowed)
				(vias allowed)
				(pads allowed)
				(copperpour not_allowed)
				(footprints allowed)
			)
			(placement
				(enabled no)
				(sheetname "")
			)
			(fill
				(thermal_gap 0.5)
				(thermal_bridge_width 0.5)
				(island_removal_mode 0)
			)
			(polygon
				(pts
					(xy 105.24744 -72.8345) (xy 106.00944 -72.8345) (xy 106.00944 -72.3265) (xy 105.24744 -72.3265)
				)
			)
		)
	)
	(footprint ""
		(layer "F.Cu")
		(at 270.654272 -77.636116)
		(property "Reference" "C5D34"
			(at 0 0 0)
			(layer "F.SilkS")
			(hide yes)
			(effects
				(font
					(size 1.27 1.27)
				)
			)
		)
		(property "Value" ""
			(at 0 0 0)
			(layer "F.Fab")
			(effects
				(font
					(size 1.27 1.27)
				)
			)
		)
		(duplicate_pad_numbers_are_jumpers no)
		(fp_poly
			(pts
				(xy -0.4953 -0.2032) (xy 0.4953 -0.2032) (xy 0.4953 1.6002) (xy -0.4953 1.6002)
			)
			(stroke
				(width 0)
				(type default)
			)
			(fill no)
			(layer "F.CrtYd")
		)
		(fp_line
			(start -0.4953 -0.2032)
			(end 0.4953 -0.2032)
			(stroke
				(width 0.1)
				(type default)
			)
			(layer "F.Fab")
		)
		(fp_line
			(start -0.4953 1.6002)
			(end -0.4953 -0.2032)
			(stroke
				(width 0.1)
				(type default)
			)
			(layer "F.Fab")
		)
		(fp_line
			(start 0.4953 -0.2032)
			(end 0.4953 1.6002)
			(stroke
				(width 0.1)
				(type default)
			)
			(layer "F.Fab")
		)
		(fp_line
			(start 0.4953 1.6002)
			(end -0.4953 1.6002)
			(stroke
				(width 0.1)
				(type default)
			)
			(layer "F.Fab")
		)
		(pad "1" smd rect
			(at 0 0)
			(size 0.762 0.889)
			(layers "F.Cu" "F.Mask" "F.Paste")
			(net "PVCCMCP_CPU0")
		)
		(pad "2" smd rect
			(at 0 1.397)
			(size 0.762 0.889)
			(layers "F.Cu" "F.Mask" "F.Paste")
			(net "GND")
		)
		(zone
			(layer "F.Cu")
			(hatch none 0.5)
			(connect_pads
				(clearance 0)
			)
			(min_thickness 0.25)
			(keepout
				(tracks not_allowed)
				(vias allowed)
				(pads allowed)
				(copperpour not_allowed)
				(footprints allowed)
			)
			(placement
				(enabled no)
				(sheetname "")
			)
			(fill
				(thermal_gap 0.5)
				(thermal_bridge_width 0.5)
				(island_removal_mode 0)
			)
			(polygon
				(pts
					(xy 270.273272 -77.191616) (xy 271.035272 -77.191616) (xy 271.035272 -76.683616) (xy 270.273272 -76.683616)
				)
			)
		)
	)
	(footprint ""
		(layer "F.Cu")
		(at 450.521832 -28.772104)
		(property "Reference" "C25W4"
			(at -0.8382 -0.67818 0)
			(unlocked yes)
			(layer "F.SilkS")
			(effects
				(font
					(size 0.4064 0.254)
					(thickness 0.1524)
				)
				(justify left)
			)
		)
		(property "Value" ""
			(at 0 0 0)
			(layer "F.Fab")
			(effects
				(font
					(size 1.27 1.27)
				)
			)
		)
		(duplicate_pad_numbers_are_jumpers no)
		(fp_poly
			(pts
				(xy 0.3048 -0.1016) (xy 0.3048 0.9906) (xy -0.3048 0.9906) (xy -0.3048 -0.1016)
			)
			(stroke
				(width 0)
				(type default)
			)
			(fill no)
			(layer "F.CrtYd")
		)
		(fp_line
			(start -0.3048 -0.1016)
			(end -0.3048 0.9906)
			(stroke
				(width 0.1)
				(type default)
			)
			(layer "F.Fab")
		)
		(fp_line
			(start -0.3048 0.9906)
			(end 0.3048 0.9906)
			(stroke
				(width 0.1)
				(type default)
			)
			(layer "F.Fab")
		)
		(fp_line
			(start 0.3048 -0.1016)
			(end -0.3048 -0.1016)
			(stroke
				(width 0.1)
				(type default)
			)
			(layer "F.Fab")
		)
		(fp_line
			(start 0.3048 0.9906)
			(end 0.3048 -0.1016)
			(stroke
				(width 0.1)
				(type default)
			)
			(layer "F.Fab")
		)
		(pad "1" smd rect
			(at 0 0)
			(size 0.508 0.508)
			(layers "F.Cu" "F.Mask" "F.Paste")
			(net "P1V2_AUX_BMC")
		)
		(pad "2" smd rect
			(at 0 0.889)
			(size 0.508 0.508)
			(layers "F.Cu" "F.Mask" "F.Paste")
			(net "GND")
		)
		(zone
			(layer "F.Cu")
			(hatch none 0.5)
			(connect_pads
				(clearance 0)
			)
			(min_thickness 0.25)
			(keepout
				(tracks allowed)
				(vias not_allowed)
				(pads allowed)
				(copperpour not_allowed)
				(footprints allowed)
			)
			(placement
				(enabled no)
				(sheetname "")
			)
			(fill
				(thermal_gap 0.5)
				(thermal_bridge_width 0.5)
				(island_removal_mode 0)
			)
			(polygon
				(pts
					(xy 450.267832 -28.518104) (xy 450.775832 -28.518104) (xy 450.775832 -28.137104) (xy 450.267832 -28.137104)
				)
			)
		)
		(zone
			(layer "F.Cu")
			(hatch none 0.5)
			(connect_pads
				(clearance 0)
			)
			(min_thickness 0.25)
			(keepout
				(tracks not_allowed)
				(vias allowed)
				(pads allowed)
				(copperpour not_allowed)
				(footprints allowed)
			)
			(placement
				(enabled no)
				(sheetname "")
			)
			(fill
				(thermal_gap 0.5)
				(thermal_bridge_width 0.5)
				(island_removal_mode 0)
			)
			(polygon
				(pts
					(xy 450.267832 -28.137104) (xy 450.775832 -28.137104) (xy 450.775832 -28.518104) (xy 450.267832 -28.518104)
				)
			)
		)
	)
	(footprint ""
		(layer "F.Cu")
		(at 174.639224 -75.004168 -90)
		(property "Reference" "R4W4"
			(at -0.8382 -0.67818 270)
			(unlocked yes)
			(layer "F.SilkS")
			(effects
				(font
					(size 0.4064 0.254)
					(thickness 0.1524)
				)
				(justify left)
			)
		)
		(property "Value" ""
			(at 0 0 270)
			(layer "F.Fab")
			(effects
				(font
					(size 1.27 1.27)
				)
			)
		)
		(duplicate_pad_numbers_are_jumpers no)
		(fp_poly
			(pts
				(xy -0.2794 -0.1016) (xy 0.2794 -0.1016) (xy 0.2794 0.9906) (xy -0.2794 0.9906)
			)
			(stroke
				(width 0)
				(type default)
			)
			(fill no)
			(layer "F.CrtYd")
		)
		(fp_line
			(start -0.2794 0.9906)
			(end 0.2794 0.9906)
			(stroke
				(width 0.1)
				(type default)
			)
			(layer "F.Fab")
		)
		(fp_line
			(start 0.2794 0.9906)
			(end 0.2794 -0.1016)
			(stroke
				(width 0.1)
				(type default)
			)
			(layer "F.Fab")
		)
		(fp_line
			(start -0.2794 -0.1016)
			(end -0.2794 0.9906)
			(stroke
				(width 0.1)
				(type default)
			)
			(layer "F.Fab")
		)
		(fp_line
			(start 0.2794 -0.1016)
			(end -0.2794 -0.1016)
			(stroke
				(width 0.1)
				(type default)
			)
			(layer "F.Fab")
		)
		(pad "1" smd rect
			(at 0 0 270)
			(size 0.508 0.508)
			(layers "F.Cu" "F.Mask" "F.Paste")
			(net "P3V3_DB1200")
		)
		(pad "2" smd rect
			(at 0 0.889 270)
			(size 0.508 0.508)
			(layers "F.Cu" "F.Mask" "F.Paste")
			(net "SMB_HOST_STBY_LVC3_SCL_R2")
		)
		(zone
			(layer "F.Cu")
			(hatch none 0.5)
			(connect_pads
				(clearance 0)
			)
			(min_thickness 0.25)
			(keepout
				(tracks not_allowed)
				(vias allowed)
				(pads allowed)
				(copperpour not_allowed)
				(footprints allowed)
			)
			(placement
				(enabled no)
				(sheetname "")
			)
			(fill
				(thermal_gap 0.5)
				(thermal_bridge_width 0.5)
				(island_removal_mode 0)
			)
			(polygon
				(pts
					(xy 174.004224 -75.258168) (xy 174.004224 -74.750168) (xy 174.385224 -74.750168) (xy 174.385224 -75.258168)
				)
			)
		)
		(zone
			(layer "F.Cu")
			(hatch none 0.5)
			(connect_pads
				(clearance 0)
			)
			(min_thickness 0.25)
			(keepout
				(tracks allowed)
				(vias not_allowed)
				(pads allowed)
				(copperpour not_allowed)
				(footprints allowed)
			)
			(placement
				(enabled no)
				(sheetname "")
			)
			(fill
				(thermal_gap 0.5)
				(thermal_bridge_width 0.5)
				(island_removal_mode 0)
			)
			(polygon
				(pts
					(xy 174.385224 -75.258168) (xy 174.385224 -74.750168) (xy 174.004224 -74.750168) (xy 174.004224 -75.258168)
				)
			)
		)
	)
	(footprint ""
		(layer "F.Cu")
		(at 19.812 -86.6267 180)
		(property "Reference" "R1D53"
			(at 0 0 180)
			(layer "F.SilkS")
			(hide yes)
			(effects
				(font
					(size 1.27 1.27)
				)
			)
		)
		(property "Value" ""
			(at 0 0 180)
			(layer "F.Fab")
			(effects
				(font
					(size 1.27 1.27)
				)
			)
		)
		(duplicate_pad_numbers_are_jumpers no)
		(fp_rect
			(start -0.2794 0.9906)
			(end 0.2794 -0.1016)
			(stroke
				(width 0)
				(type default)
			)
			(fill no)
			(layer "F.CrtYd")
		)
		(fp_line
			(start 0.2794 0.9906)
			(end 0.2794 -0.1016)
			(stroke
				(width 0.1)
				(type default)
			)
			(layer "F.Fab")
		)
		(fp_line
			(start 0.2794 -0.1016)
			(end -0.2794 -0.1016)
			(stroke
				(width 0.1)
				(type default)
			)
			(layer "F.Fab")
		)
		(fp_line
			(start -0.2794 0.9906)
			(end 0.2794 0.9906)
			(stroke
				(width 0.1)
				(type default)
			)
			(layer "F.Fab")
		)
		(fp_line
			(start -0.2794 -0.1016)
			(end -0.2794 0.9906)
			(stroke
				(width 0.1)
				(type default)
			)
			(layer "F.Fab")
		)
		(pad "1" smd rect
			(at 0 0 180)
			(size 0.508 0.508)
			(layers "F.Cu" "F.Mask" "F.Paste")
			(net "P3V3_STBY")
		)
		(pad "2" smd rect
			(at 0 0.889 180)
			(size 0.508 0.508)
			(layers "F.Cu" "F.Mask" "F.Paste")
			(net "PU_VR_PVCCIN_CPU1_FLT1_SMBALT_N")
		)
		(zone
			(layer "F.Cu")
			(hatch none 0.5)
			(connect_pads
				(clearance 0)
			)
			(min_thickness 0.25)
			(keepout
				(tracks allowed)
				(vias not_allowed)
				(pads allowed)
				(copperpour not_allowed)
				(footprints allowed)
			)
			(placement
				(enabled no)
				(sheetname "")
			)
			(fill
				(thermal_gap 0.5)
				(thermal_bridge_width 0.5)
				(island_removal_mode 0)
			)
			(polygon
				(pts
					(xy 20.066 -87.2617) (xy 19.558 -87.2617) (xy 19.558 -86.8807) (xy 20.066 -86.8807)
				)
			)
		)
		(zone
			(layer "F.Cu")
			(hatch none 0.5)
			(connect_pads
				(clearance 0)
			)
			(min_thickness 0.25)
			(keepout
				(tracks not_allowed)
				(vias allowed)
				(pads allowed)
				(copperpour not_allowed)
				(footprints allowed)
			)
			(placement
				(enabled no)
				(sheetname "")
			)
			(fill
				(thermal_gap 0.5)
				(thermal_bridge_width 0.5)
				(island_removal_mode 0)
			)
			(polygon
				(pts
					(xy 20.066 -87.2617) (xy 19.558 -87.2617) (xy 19.558 -86.8807) (xy 20.066 -86.8807)
				)
			)
		)
	)
	(footprint ""
		(layer "F.Cu")
		(at 330.835 -12.8016 180)
		(property "Reference" "C6G3"
			(at 0 0 180)
			(layer "F.SilkS")
			(hide yes)
			(effects
				(font
					(size 1.27 1.27)
				)
			)
		)
		(property "Value" ""
			(at 0 0 180)
			(layer "F.Fab")
			(effects
				(font
					(size 1.27 1.27)
				)
			)
		)
		(duplicate_pad_numbers_are_jumpers no)
		(fp_rect
			(start 0.7239 -0.2159)
			(end -0.7239 1.9939)
			(stroke
				(width 0)
				(type default)
			)
			(fill no)
			(layer "F.CrtYd")
		)
		(fp_line
			(start 0.7239 1.9939)
			(end 0.7239 -0.2159)
			(stroke
				(width 0.1)
				(type default)
			)
			(layer "F.Fab")
		)
		(fp_line
			(start 0.7239 -0.2159)
			(end -0.7239 -0.2159)
			(stroke
				(width 0.1)
				(type default)
			)
			(layer "F.Fab")
		)
		(fp_line
			(start -0.7239 1.9939)
			(end 0.7239 1.9939)
			(stroke
				(width 0.1)
				(type default)
			)
			(layer "F.Fab")
		)
		(fp_line
			(start -0.7239 -0.2159)
			(end -0.7239 1.9939)
			(stroke
				(width 0.1)
				(type default)
			)
			(layer "F.Fab")
		)
		(pad "1" smd rect
			(at 0 0 180)
			(size 1.27 1.016)
			(layers "F.Cu" "F.Mask" "F.Paste")
			(net "PVDDQ_ABC")
		)
		(pad "2" smd rect
			(at 0 1.778 180)
			(size 1.27 1.016)
			(layers "F.Cu" "F.Mask" "F.Paste")
			(net "GND")
		)
		(zone
			(layer "F.Cu")
			(hatch none 0.5)
			(connect_pads
				(clearance 0)
			)
			(min_thickness 0.25)
			(keepout
				(tracks not_allowed)
				(vias allowed)
				(pads allowed)
				(copperpour not_allowed)
				(footprints allowed)
			)
			(placement
				(enabled no)
				(sheetname "")
			)
			(fill
				(thermal_gap 0.5)
				(thermal_bridge_width 0.5)
				(island_removal_mode 0)
			)
			(polygon
				(pts
					(xy 330.2 -13.3096) (xy 331.47 -13.3096) (xy 331.47 -14.0716) (xy 330.2 -14.0716)
				)
			)
		)
	)
)
